# S9S_MB_2U (Grand Teton) — schematic netlist excerpt (pin names and nets, part order shuffled) for the footprints in the layout excerpt that follows; sources: Cadence DE-HDL packaged netlist, KiCad conversion of 03242023_DA0F0TMBIJ0_F0T_Motherboard_J_brd_V01_OCP.brd

R422  Q_RES  10K 1% CHIP  pkg 0402LF  page 153 : A = SGPIO_OCP_SFF_DATAOUT ; B = GND
PR2515  Q_RES  10 1% EMPTY  pkg 0402LF  page 304 : A = P12V_HSC_ADC_N ; B = P12V_HSC_SENSE2_R1_N

(kicad_pcb
	(version 20260206)
	(generator "pcbnew")
	(generator_version "10.0")
	(general
		(thickness 1.6)
		(legacy_teardrops no)
	)
	(paper "A4")
	(title_block
		(title "03242023_DA0F0TMBIJ0_F0T_Motherboard_J_brd_V01_OCP.brd")
		(comment 1 "Grand Teton / footprints 4333-4334 of 6105")
	)
	(layers
		(0 "F.Cu" signal "TOP")
		(4 "In1.Cu" signal "GND")
		(6 "In2.Cu" signal "IN1")
		(8 "In3.Cu" signal "GND1")
		(10 "In4.Cu" signal "IN2")
		(12 "In5.Cu" signal "GND2")
		(14 "In6.Cu" signal "IN3")
		(16 "In7.Cu" signal "GND3")
		(18 "In8.Cu" signal "VCC")
		(20 "In9.Cu" signal "VCC1")
		(22 "In10.Cu" signal "GND4")
		(24 "In11.Cu" signal "IN4")
		(26 "In12.Cu" signal "GND5")
		(28 "In13.Cu" signal "IN5")
		(30 "In14.Cu" signal "GND6")
		(32 "In15.Cu" signal "IN6")
		(34 "In16.Cu" signal "GND7")
		(2 "B.Cu" signal "BOTTOM")
		(9 "F.Adhes" user "F.Adhesive")
		(11 "B.Adhes" user "B.Adhesive")
		(13 "F.Paste" user "Package Geometry/Pastemask Top")
		(15 "B.Paste" user "Package Geometry/Pastemask Bottom")
		(5 "F.SilkS" user "Ref Des/Silkscreen Top")
		(7 "B.SilkS" user "Ref Des/Silkscreen Bottom")
		(1 "F.Mask" user "Board Geometry/Soldermask Top")
		(3 "B.Mask" user "Board Geometry/Soldermask Bottom")
		(17 "Dwgs.User" user "User.Drawings")
		(19 "Cmts.User" user "User.Comments")
		(21 "Eco1.User" user "User.Eco1")
		(23 "Eco2.User" user "User.Eco2")
		(25 "Edge.Cuts" user "Board Geometry/Outline")
		(27 "Margin" user)
		(31 "F.CrtYd" user "Package Geometry/Place Bound Top")
		(29 "B.CrtYd" user "Package Geometry/Place Bound Bottom")
		(35 "F.Fab" user "Ref Des/Assembly Top")
		(33 "B.Fab" user "Ref Des/Assembly Bottom")
	)
	(footprint ""
		(layer "B.Cu")
		(at 450.482716 -10.594086 90)
		(property "Reference" "R422"
			(at 0 0 90)
			(layer "B.SilkS")
			(hide yes)
			(effects
				(font
					(size 1.27 1.27)
				)
				(justify mirror)
			)
		)
		(property "Value" ""
			(at 0 0 90)
			(layer "B.Fab")
			(effects
				(font
					(size 1.27 1.27)
				)
				(justify mirror)
			)
		)
		(duplicate_pad_numbers_are_jumpers no)
		(fp_line
			(start 0.7874 -0.4064)
			(end -0.7874 -0.4064)
			(stroke
				(width 0.1524)
				(type default)
			)
			(layer "B.SilkS")
		)
		(fp_line
			(start -0.7874 -0.4064)
			(end -0.7874 0.4064)
			(stroke
				(width 0.1524)
				(type default)
			)
			(layer "B.SilkS")
		)
		(fp_line
			(start 0.7874 0.4064)
			(end 0.7874 -0.4064)
			(stroke
				(width 0.1524)
				(type default)
			)
			(layer "B.SilkS")
		)
		(fp_line
			(start -0.7874 0.4064)
			(end 0.7874 0.4064)
			(stroke
				(width 0.1524)
				(type default)
			)
			(layer "B.SilkS")
		)
		(fp_line
			(start 0.67945 -0.305054)
			(end 0.12065 -0.305054)
			(stroke
				(width 0.1)
				(type default)
			)
			(layer "B.Fab")
		)
		(fp_line
			(start 0.12065 -0.305054)
			(end 0.12065 -0.2794)
			(stroke
				(width 0.1)
				(type default)
			)
			(layer "B.Fab")
		)
		(fp_line
			(start -0.12065 -0.3048)
			(end -0.67945 -0.3048)
			(stroke
				(width 0.1)
				(type default)
			)
			(layer "B.Fab")
		)
		(fp_line
			(start -0.67945 -0.3048)
			(end -0.67945 0.3048)
			(stroke
				(width 0.1)
				(type default)
			)
			(layer "B.Fab")
		)
		(fp_line
			(start 0.12065 -0.2794)
			(end -0.12065 -0.2794)
			(stroke
				(width 0.1)
				(type default)
			)
			(layer "B.Fab")
		)
		(fp_line
			(start -0.12065 -0.2794)
			(end -0.12065 -0.3048)
			(stroke
				(width 0.1)
				(type default)
			)
			(layer "B.Fab")
		)
		(fp_line
			(start 0.12065 0.2794)
			(end 0.12065 0.3048)
			(stroke
				(width 0.1)
				(type default)
			)
			(layer "B.Fab")
		)
		(fp_line
			(start -0.120396 0.2794)
			(end 0.12065 0.2794)
			(stroke
				(width 0.1)
				(type default)
			)
			(layer "B.Fab")
		)
		(fp_line
			(start 0.67945 0.3048)
			(end 0.67945 -0.305054)
			(stroke
				(width 0.1)
				(type default)
			)
			(layer "B.Fab")
		)
		(fp_line
			(start 0.12065 0.3048)
			(end 0.67945 0.3048)
			(stroke
				(width 0.1)
				(type default)
			)
			(layer "B.Fab")
		)
		(fp_line
			(start -0.120396 0.3048)
			(end -0.120396 0.2794)
			(stroke
				(width 0.1)
				(type default)
			)
			(layer "B.Fab")
		)
		(fp_line
			(start -0.67945 0.3048)
			(end -0.120396 0.3048)
			(stroke
				(width 0.1)
				(type default)
			)
			(layer "B.Fab")
		)
		(pad "1" smd circle
			(at 0.40005 0 270)
			(size 0 0)
			(layers "B.Cu" "B.Mask" "B.Paste")
			(net "SGPIO_OCP_SFF_DATAOUT")
		)
		(pad "2" smd circle
			(at -0.40005 0 270)
			(size 0 0)
			(layers "B.Cu" "B.Mask" "B.Paste")
			(net "GND")
		)
	)
	(footprint ""
		(layer "B.Cu")
		(at 297.45813 -403.031452 90)
		(property "Reference" "PR2515"
			(at 0 0 90)
			(layer "B.SilkS")
			(hide yes)
			(effects
				(font
					(size 1.27 1.27)
				)
				(justify mirror)
			)
		)
		(property "Value" ""
			(at 0 0 90)
			(layer "B.Fab")
			(effects
				(font
					(size 1.27 1.27)
				)
				(justify mirror)
			)
		)
		(duplicate_pad_numbers_are_jumpers no)
		(fp_line
			(start 0.7874 -0.4064)
			(end -0.7874 -0.4064)
			(stroke
				(width 0.1524)
				(type default)
			)
			(layer "B.SilkS")
		)
		(fp_line
			(start -0.7874 -0.4064)
			(end -0.7874 0.4064)
			(stroke
				(width 0.1524)
				(type default)
			)
			(layer "B.SilkS")
		)
		(fp_line
			(start 0.7874 0.4064)
			(end 0.7874 -0.4064)
			(stroke
				(width 0.1524)
				(type default)
			)
			(layer "B.SilkS")
		)
		(fp_line
			(start -0.7874 0.4064)
			(end 0.7874 0.4064)
			(stroke
				(width 0.1524)
				(type default)
			)
			(layer "B.SilkS")
		)
		(fp_line
			(start 0.67945 -0.305054)
			(end 0.12065 -0.305054)
			(stroke
				(width 0.1)
				(type default)
			)
			(layer "B.Fab")
		)
		(fp_line
			(start 0.12065 -0.305054)
			(end 0.12065 -0.2794)
			(stroke
				(width 0.1)
				(type default)
			)
			(layer "B.Fab")
		)
		(fp_line
			(start -0.12065 -0.3048)
			(end -0.67945 -0.3048)
			(stroke
				(width 0.1)
				(type default)
			)
			(layer "B.Fab")
		)
		(fp_line
			(start -0.67945 -0.3048)
			(end -0.67945 0.3048)
			(stroke
				(width 0.1)
				(type default)
			)
			(layer "B.Fab")
		)
		(fp_line
			(start 0.12065 -0.2794)
			(end -0.12065 -0.2794)
			(stroke
				(width 0.1)
				(type default)
			)
			(layer "B.Fab")
		)
		(fp_line
			(start -0.12065 -0.2794)
			(end -0.12065 -0.3048)
			(stroke
				(width 0.1)
				(type default)
			)
			(layer "B.Fab")
		)
		(fp_line
			(start 0.12065 0.2794)
			(end 0.12065 0.3048)
			(stroke
				(width 0.1)
				(type default)
			)
			(layer "B.Fab")
		)
		(fp_line
			(start -0.120396 0.2794)
			(end 0.12065 0.2794)
			(stroke
				(width 0.1)
				(type default)
			)
			(layer "B.Fab")
		)
		(fp_line
			(start 0.67945 0.3048)
			(end 0.67945 -0.305054)
			(stroke
				(width 0.1)
				(type default)
			)
			(layer "B.Fab")
		)
		(fp_line
			(start 0.12065 0.3048)
			(end 0.67945 0.3048)
			(stroke
				(width 0.1)
				(type default)
			)
			(layer "B.Fab")
		)
		(fp_line
			(start -0.120396 0.3048)
			(end -0.120396 0.2794)
			(stroke
				(width 0.1)
				(type default)
			)
			(layer "B.Fab")
		)
		(fp_line
			(start -0.67945 0.3048)
			(end -0.120396 0.3048)
			(stroke
				(width 0.1)
				(type default)
			)
			(layer "B.Fab")
		)
		(pad "1" smd circle
			(at 0.40005 0 270)
			(size 0 0)
			(layers "B.Cu" "B.Mask" "B.Paste")
			(net "P12V_HSC_ADC_N")
		)
		(pad "2" smd circle
			(at -0.40005 0 270)
			(size 0 0)
			(layers "B.Cu" "B.Mask" "B.Paste")
			(net "P12V_HSC_SENSE2_R1_N")
		)
	)
)
